(kicad_pcb
	(version 20260206)
	(generator "pcbnew")
	(generator_version "10.0")
	(general
		(thickness 1.6)
		(legacy_teardrops no)
	)
	(paper "A4")
	(title_block
		(title "12092022_DA0F0TFB6D0_F0T_FAN_BOARD_MP5048_D_brd_v02_OCP.brd")
		(comment 1 "Grand Teton / footprints 398-403 of 924")
	)
	(layers
		(0 "F.Cu" signal "TOP")
		(4 "In1.Cu" signal "GND")
		(6 "In2.Cu" signal "IN1")
		(8 "In3.Cu" signal "IN2")
		(10 "In4.Cu" signal "GND1")
		(2 "B.Cu" signal "BOTTOM")
		(9 "F.Adhes" user "F.Adhesive")
		(11 "B.Adhes" user "B.Adhesive")
		(13 "F.Paste" user "Package Geometry/Pastemask Top")
		(15 "B.Paste" user "Package Geometry/Pastemask Bottom")
		(5 "F.SilkS" user "Ref Des/Silkscreen Top")
		(7 "B.SilkS" user "Ref Des/Silkscreen Bottom")
		(1 "F.Mask" user "Board Geometry/Soldermask Top")
		(3 "B.Mask" user "Board Geometry/Soldermask Bottom")
		(17 "Dwgs.User" user "User.Drawings")
		(19 "Cmts.User" user "User.Comments")
		(21 "Eco1.User" user "User.Eco1")
		(23 "Eco2.User" user "User.Eco2")
		(25 "Edge.Cuts" user "Board Geometry/Outline")
		(27 "Margin" user)
		(31 "F.CrtYd" user "Package Geometry/Place Bound Top")
		(29 "B.CrtYd" user "Package Geometry/Place Bound Bottom")
		(35 "F.Fab" user "Ref Des/Assembly Top")
		(33 "B.Fab" user "Ref Des/Assembly Bottom")
	)
	(footprint ""
		(layer "F.Cu")
		(at 25.527 -122.78995 180)
		(property "Reference" "R5461"
			(at 0 0 180)
			(layer "F.SilkS")
			(hide yes)
			(effects
				(font
					(size 1.27 1.27)
				)
			)
		)
		(property "Value" ""
			(at 0 0 180)
			(layer "F.Fab")
			(effects
				(font
					(size 1.27 1.27)
				)
			)
		)
		(duplicate_pad_numbers_are_jumpers no)
		(fp_line
			(start 0.7874 0.4064)
			(end -0.7874 0.4064)
			(stroke
				(width 0.1524)
				(type default)
			)
			(layer "F.SilkS")
		)
		(fp_line
			(start 0.7874 -0.4064)
			(end 0.7874 0.4064)
			(stroke
				(width 0.1524)
				(type default)
			)
			(layer "F.SilkS")
		)
		(fp_line
			(start -0.7874 0.4064)
			(end -0.7874 -0.4064)
			(stroke
				(width 0.1524)
				(type default)
			)
			(layer "F.SilkS")
		)
		(fp_line
			(start -0.7874 -0.4064)
			(end 0.7874 -0.4064)
			(stroke
				(width 0.1524)
				(type default)
			)
			(layer "F.SilkS")
		)
		(fp_line
			(start 0.67945 0.3048)
			(end 0.120396 0.3048)
			(stroke
				(width 0.1)
				(type default)
			)
			(layer "F.Fab")
		)
		(fp_line
			(start 0.67945 -0.3048)
			(end 0.67945 0.3048)
			(stroke
				(width 0.1)
				(type default)
			)
			(layer "F.Fab")
		)
		(fp_line
			(start 0.12065 -0.2794)
			(end 0.12065 -0.3048)
			(stroke
				(width 0.1)
				(type default)
			)
			(layer "F.Fab")
		)
		(fp_line
			(start 0.12065 -0.3048)
			(end 0.67945 -0.3048)
			(stroke
				(width 0.1)
				(type default)
			)
			(layer "F.Fab")
		)
		(fp_line
			(start 0.120396 0.3048)
			(end 0.120396 0.2794)
			(stroke
				(width 0.1)
				(type default)
			)
			(layer "F.Fab")
		)
		(fp_line
			(start 0.120396 0.2794)
			(end -0.12065 0.2794)
			(stroke
				(width 0.1)
				(type default)
			)
			(layer "F.Fab")
		)
		(fp_line
			(start -0.12065 0.3048)
			(end -0.67945 0.3048)
			(stroke
				(width 0.1)
				(type default)
			)
			(layer "F.Fab")
		)
		(fp_line
			(start -0.12065 0.2794)
			(end -0.12065 0.3048)
			(stroke
				(width 0.1)
				(type default)
			)
			(layer "F.Fab")
		)
		(fp_line
			(start -0.12065 -0.2794)
			(end 0.12065 -0.2794)
			(stroke
				(width 0.1)
				(type default)
			)
			(layer "F.Fab")
		)
		(fp_line
			(start -0.12065 -0.305054)
			(end -0.12065 -0.2794)
			(stroke
				(width 0.1)
				(type default)
			)
			(layer "F.Fab")
		)
		(fp_line
			(start -0.67945 0.3048)
			(end -0.67945 -0.305054)
			(stroke
				(width 0.1)
				(type default)
			)
			(layer "F.Fab")
		)
		(fp_line
			(start -0.67945 -0.305054)
			(end -0.12065 -0.305054)
			(stroke
				(width 0.1)
				(type default)
			)
			(layer "F.Fab")
		)
		(pad "1" smd circle
			(at -0.40005 0 180)
			(size 0 0)
			(layers "F.Cu" "F.Mask" "F.Paste")
			(net "SMB_PDBV_FAN_SCL")
		)
		(pad "2" smd circle
			(at 0.40005 0 180)
			(size 0 0)
			(layers "F.Cu" "F.Mask" "F.Paste")
			(net "SMB_PDBV_FAN_R_U330_SCL")
		)
	)
	(footprint ""
		(layer "F.Cu")
		(at 36.195 -181.61)
		(property "Reference" "U390"
			(at -0.635 3.32867 0)
			(unlocked yes)
			(layer "F.SilkS")
			(effects
				(font
					(size 0.7874 0.5842)
					(thickness 0.1524)
				)
				(justify left)
			)
		)
		(property "Value" ""
			(at 0 0 0)
			(layer "F.Fab")
			(effects
				(font
					(size 1.27 1.27)
				)
			)
		)
		(duplicate_pad_numbers_are_jumpers no)
		(fp_line
			(start -2.0066 -2.5527)
			(end -0.5715 -2.5527)
			(stroke
				(width 0.1524)
				(type default)
			)
			(layer "F.SilkS")
		)
		(fp_line
			(start -2.0066 2.5527)
			(end -2.0066 -2.5527)
			(stroke
				(width 0.1524)
				(type default)
			)
			(layer "F.SilkS")
		)
		(fp_line
			(start -0.5715 -2.5527)
			(end 0 -1.9812)
			(stroke
				(width 0.1524)
				(type default)
			)
			(layer "F.SilkS")
		)
		(fp_line
			(start 0 -1.9812)
			(end 0.5715 -2.5527)
			(stroke
				(width 0.1524)
				(type default)
			)
			(layer "F.SilkS")
		)
		(fp_line
			(start 0.5715 -2.5527)
			(end 2.0066 -2.5527)
			(stroke
				(width 0.1524)
				(type default)
			)
			(layer "F.SilkS")
		)
		(fp_line
			(start 2.0066 -2.5527)
			(end 2.0066 2.5527)
			(stroke
				(width 0.1524)
				(type default)
			)
			(layer "F.SilkS")
		)
		(fp_line
			(start 2.0066 2.5527)
			(end -2.0066 2.5527)
			(stroke
				(width 0.1524)
				(type default)
			)
			(layer "F.SilkS")
		)
		(fp_poly
			(pts
				(xy -4.36372 -1.608328) (xy -4.36372 -2.233168) (xy -3.81 -1.905)
			)
			(stroke
				(width 0)
				(type default)
			)
			(fill yes)
			(layer "F.SilkS")
		)
		(fp_line
			(start -2.249932 -2.549906)
			(end 2.249932 -2.549906)
			(stroke
				(width 0.1)
				(type default)
			)
			(layer "F.Fab")
		)
		(fp_line
			(start -2.249932 2.549906)
			(end -2.249932 -2.549906)
			(stroke
				(width 0.1)
				(type default)
			)
			(layer "F.Fab")
		)
		(fp_line
			(start 2.249932 -2.549906)
			(end 2.249932 2.549906)
			(stroke
				(width 0.1)
				(type default)
			)
			(layer "F.Fab")
		)
		(fp_line
			(start 2.249932 2.549906)
			(end -2.249932 2.549906)
			(stroke
				(width 0.1)
				(type default)
			)
			(layer "F.Fab")
		)
		(fp_poly
			(pts
				(xy -4.36372 -1.608328) (xy -4.36372 -2.233168) (xy -3.81 -1.905)
			)
			(stroke
				(width 0)
				(type default)
			)
			(fill yes)
			(layer "F.Fab")
		)
		(pad "1" smd rect
			(at -2.921 -1.949958 270)
			(size 0.3556 1.4986)
			(layers "F.Cu" "F.Mask" "F.Paste")
			(net "P52V_FAN_BUFF_EN_R")
		)
		(pad "2" smd rect
			(at -2.921 -1.299972 270)
			(size 0.3556 1.4986)
			(layers "F.Cu" "F.Mask" "F.Paste")
			(net "P52V_FAN_0_BUFF_EN")
		)
		(pad "3" smd rect
			(at -2.921 -0.649986 270)
			(size 0.3556 1.4986)
			(layers "F.Cu" "F.Mask" "F.Paste")
			(net "P52V_FAN_BUFF_EN_R")
		)
		(pad "4" smd rect
			(at -2.921 0 270)
			(size 0.3556 1.4986)
			(layers "F.Cu" "F.Mask" "F.Paste")
			(net "P52V_FAN_1_BUFF_EN")
		)
		(pad "5" smd rect
			(at -2.921 0.649986 270)
			(size 0.3556 1.4986)
			(layers "F.Cu" "F.Mask" "F.Paste")
			(net "P52V_FAN_BUFF_EN_R")
		)
		(pad "6" smd rect
			(at -2.921 1.299972 270)
			(size 0.3556 1.4986)
			(layers "F.Cu" "F.Mask" "F.Paste")
			(net "P52V_FAN_2_BUFF_EN")
		)
		(pad "7" smd rect
			(at -2.921 1.949958 270)
			(size 0.3556 1.4986)
			(layers "F.Cu" "F.Mask" "F.Paste")
			(net "GND")
		)
		(pad "8" smd rect
			(at 2.921 1.949958 270)
			(size 0.3556 1.4986)
			(layers "F.Cu" "F.Mask" "F.Paste")
			(net "P52V_FAN_3_BUFF_EN")
		)
		(pad "9" smd rect
			(at 2.921 1.299972 270)
			(size 0.3556 1.4986)
			(layers "F.Cu" "F.Mask" "F.Paste")
			(net "P52V_FAN_BUFF_EN_R")
		)
		(pad "10" smd rect
			(at 2.921 0.649986 270)
			(size 0.3556 1.4986)
			(layers "F.Cu" "F.Mask" "F.Paste")
			(net "NC_U390_E")
		)
		(pad "11" smd rect
			(at 2.921 0 270)
			(size 0.3556 1.4986)
			(layers "F.Cu" "F.Mask" "F.Paste")
			(net "PD_FAN_BUFF_INPUT_U336E")
		)
		(pad "12" smd rect
			(at 2.921 -0.649986 270)
			(size 0.3556 1.4986)
			(layers "F.Cu" "F.Mask" "F.Paste")
			(net "NC_U390_F")
		)
		(pad "13" smd rect
			(at 2.921 -1.299972 270)
			(size 0.3556 1.4986)
			(layers "F.Cu" "F.Mask" "F.Paste")
			(net "PD_FAN_BUFF_INPUT_U336F")
		)
		(pad "14" smd rect
			(at 2.921 -1.949958 270)
			(size 0.3556 1.4986)
			(layers "F.Cu" "F.Mask" "F.Paste")
			(net "P3V3_AUX")
		)
	)
	(footprint ""
		(layer "F.Cu")
		(at 45.466 -217.424 90)
		(property "Reference" "R5649"
			(at 0 0 90)
			(layer "F.SilkS")
			(hide yes)
			(effects
				(font
					(size 1.27 1.27)
				)
			)
		)
		(property "Value" ""
			(at 0 0 90)
			(layer "F.Fab")
			(effects
				(font
					(size 1.27 1.27)
				)
			)
		)
		(duplicate_pad_numbers_are_jumpers no)
		(fp_line
			(start 0.7874 -0.4064)
			(end 0.7874 0.4064)
			(stroke
				(width 0.1524)
				(type default)
			)
			(layer "F.SilkS")
		)
		(fp_line
			(start -0.7874 -0.4064)
			(end 0.7874 -0.4064)
			(stroke
				(width 0.1524)
				(type default)
			)
			(layer "F.SilkS")
		)
		(fp_line
			(start 0.7874 0.4064)
			(end -0.7874 0.4064)
			(stroke
				(width 0.1524)
				(type default)
			)
			(layer "F.SilkS")
		)
		(fp_line
			(start -0.7874 0.4064)
			(end -0.7874 -0.4064)
			(stroke
				(width 0.1524)
				(type default)
			)
			(layer "F.SilkS")
		)
		(fp_line
			(start -0.12065 -0.305054)
			(end -0.12065 -0.2794)
			(stroke
				(width 0.1)
				(type default)
			)
			(layer "F.Fab")
		)
		(fp_line
			(start -0.67945 -0.305054)
			(end -0.12065 -0.305054)
			(stroke
				(width 0.1)
				(type default)
			)
			(layer "F.Fab")
		)
		(fp_line
			(start 0.67945 -0.3048)
			(end 0.67945 0.3048)
			(stroke
				(width 0.1)
				(type default)
			)
			(layer "F.Fab")
		)
		(fp_line
			(start 0.12065 -0.3048)
			(end 0.67945 -0.3048)
			(stroke
				(width 0.1)
				(type default)
			)
			(layer "F.Fab")
		)
		(fp_line
			(start 0.12065 -0.2794)
			(end 0.12065 -0.3048)
			(stroke
				(width 0.1)
				(type default)
			)
			(layer "F.Fab")
		)
		(fp_line
			(start -0.12065 -0.2794)
			(end 0.12065 -0.2794)
			(stroke
				(width 0.1)
				(type default)
			)
			(layer "F.Fab")
		)
		(fp_line
			(start 0.120396 0.2794)
			(end -0.12065 0.2794)
			(stroke
				(width 0.1)
				(type default)
			)
			(layer "F.Fab")
		)
		(fp_line
			(start -0.12065 0.2794)
			(end -0.12065 0.3048)
			(stroke
				(width 0.1)
				(type default)
			)
			(layer "F.Fab")
		)
		(fp_line
			(start 0.67945 0.3048)
			(end 0.120396 0.3048)
			(stroke
				(width 0.1)
				(type default)
			)
			(layer "F.Fab")
		)
		(fp_line
			(start 0.120396 0.3048)
			(end 0.120396 0.2794)
			(stroke
				(width 0.1)
				(type default)
			)
			(layer "F.Fab")
		)
		(fp_line
			(start -0.12065 0.3048)
			(end -0.67945 0.3048)
			(stroke
				(width 0.1)
				(type default)
			)
			(layer "F.Fab")
		)
		(fp_line
			(start -0.67945 0.3048)
			(end -0.67945 -0.305054)
			(stroke
				(width 0.1)
				(type default)
			)
			(layer "F.Fab")
		)
		(pad "1" smd rect
			(at -0.40005 0 270)
			(size 0.4572 0.508)
			(layers "F.Cu" "F.Mask" "F.Paste")
			(net "P12V_LED")
		)
		(pad "2" smd rect
			(at 0.40005 0 270)
			(size 0.4572 0.508)
			(layers "F.Cu" "F.Mask" "F.Paste")
			(net "U406_D1")
		)
	)
	(footprint ""
		(layer "F.Cu")
		(at 34.417 -18.542)
		(property "Reference" "U375"
			(at 4.064 0.28067 0)
			(unlocked yes)
			(layer "F.SilkS")
			(effects
				(font
					(size 0.7874 0.5842)
					(thickness 0.1524)
				)
				(justify left)
			)
		)
		(property "Value" ""
			(at 0 0 0)
			(layer "F.Fab")
			(effects
				(font
					(size 1.27 1.27)
				)
			)
		)
		(duplicate_pad_numbers_are_jumpers no)
		(fp_line
			(start -1.335278 -1.100074)
			(end -1.335278 1.100074)
			(stroke
				(width 0.1524)
				(type default)
			)
			(layer "F.SilkS")
		)
		(fp_line
			(start -1.335278 1.100074)
			(end 1.335278 1.100074)
			(stroke
				(width 0.1524)
				(type default)
			)
			(layer "F.SilkS")
		)
		(fp_line
			(start 1.335278 -1.100074)
			(end -1.335278 -1.100074)
			(stroke
				(width 0.1524)
				(type default)
			)
			(layer "F.SilkS")
		)
		(fp_line
			(start 1.335278 1.100074)
			(end 1.335278 -1.100074)
			(stroke
				(width 0.1524)
				(type default)
			)
			(layer "F.SilkS")
		)
		(fp_line
			(start -0.674878 -1.100074)
			(end -0.674878 1.100074)
			(stroke
				(width 0.1)
				(type default)
			)
			(layer "F.Fab")
		)
		(fp_line
			(start -0.674878 1.100074)
			(end 0.674878 1.100074)
			(stroke
				(width 0.1)
				(type default)
			)
			(layer "F.Fab")
		)
		(fp_line
			(start 0.674878 -1.100074)
			(end -0.674878 -1.100074)
			(stroke
				(width 0.1)
				(type default)
			)
			(layer "F.Fab")
		)
		(fp_line
			(start 0.674878 1.100074)
			(end 0.674878 -1.100074)
			(stroke
				(width 0.1)
				(type default)
			)
			(layer "F.Fab")
		)
		(pad "D" smd rect
			(at 0.8001 0 270)
			(size 0.6096 0.8128)
			(layers "F.Cu" "F.Mask" "F.Paste")
			(net "FAN_3_OK_LED_R_N")
		)
		(pad "G" smd rect
			(at -0.8001 -0.649986 270)
			(size 0.6096 0.8128)
			(layers "F.Cu" "F.Mask" "F.Paste")
			(net "FAN_3_OK_R_LED")
		)
		(pad "S" smd rect
			(at -0.8001 0.649986 270)
			(size 0.6096 0.8128)
			(layers "F.Cu" "F.Mask" "F.Paste")
			(net "GND")
		)
	)
	(footprint ""
		(layer "F.Cu")
		(at 8.001 -311.15 -90)
		(property "Reference" "Q16"
			(at 0.70866 -2.54635 90)
			(unlocked yes)
			(layer "F.SilkS")
			(effects
				(font
					(size 0.7874 0.5842)
					(thickness 0.1524)
				)
				(justify left)
			)
		)
		(property "Value" ""
			(at 0 0 270)
			(layer "F.Fab")
			(effects
				(font
					(size 1.27 1.27)
				)
			)
		)
		(duplicate_pad_numbers_are_jumpers no)
		(fp_line
			(start -1.905 1.651)
			(end -1.905 -1.651)
			(stroke
				(width 0.1524)
				(type default)
			)
			(layer "F.SilkS")
		)
		(fp_line
			(start 1.905 1.651)
			(end -1.905 1.651)
			(stroke
				(width 0.1524)
				(type default)
			)
			(layer "F.SilkS")
		)
		(fp_line
			(start -1.905 -1.651)
			(end 1.905 -1.651)
			(stroke
				(width 0.1524)
				(type default)
			)
			(layer "F.SilkS")
		)
		(fp_line
			(start 1.905 -1.651)
			(end 1.905 1.651)
			(stroke
				(width 0.1524)
				(type default)
			)
			(layer "F.SilkS")
		)
		(fp_line
			(start -0.6985 1.524)
			(end -0.6985 1.169924)
			(stroke
				(width 0.1)
				(type default)
			)
			(layer "F.Fab")
		)
		(fp_line
			(start 0.6985 1.524)
			(end -0.6985 1.524)
			(stroke
				(width 0.1)
				(type default)
			)
			(layer "F.Fab")
		)
		(fp_line
			(start -1.249934 1.169924)
			(end -1.249934 0.729996)
			(stroke
				(width 0.1)
				(type default)
			)
			(layer "F.Fab")
		)
		(fp_line
			(start -0.6985 1.169924)
			(end -1.249934 1.169924)
			(stroke
				(width 0.1)
				(type default)
			)
			(layer "F.Fab")
		)
		(fp_line
			(start -1.249934 0.729996)
			(end -0.6985 0.729996)
			(stroke
				(width 0.1)
				(type default)
			)
			(layer "F.Fab")
		)
		(fp_line
			(start -0.6985 0.729996)
			(end -0.6985 -0.729996)
			(stroke
				(width 0.1)
				(type default)
			)
			(layer "F.Fab")
		)
		(fp_line
			(start 0.6985 0.219964)
			(end 0.6985 1.524)
			(stroke
				(width 0.1)
				(type default)
			)
			(layer "F.Fab")
		)
		(fp_line
			(start 1.249934 0.219964)
			(end 0.6985 0.219964)
			(stroke
				(width 0.1)
				(type default)
			)
			(layer "F.Fab")
		)
		(fp_line
			(start 0.6985 -0.219964)
			(end 1.249934 -0.219964)
			(stroke
				(width 0.1)
				(type default)
			)
			(layer "F.Fab")
		)
		(fp_line
			(start 1.249934 -0.219964)
			(end 1.249934 0.219964)
			(stroke
				(width 0.1)
				(type default)
			)
			(layer "F.Fab")
		)
		(fp_line
			(start -1.249934 -0.729996)
			(end -1.249934 -1.169924)
			(stroke
				(width 0.1)
				(type default)
			)
			(layer "F.Fab")
		)
		(fp_line
			(start -0.6985 -0.729996)
			(end -1.249934 -0.729996)
			(stroke
				(width 0.1)
				(type default)
			)
			(layer "F.Fab")
		)
		(fp_line
			(start -1.249934 -1.169924)
			(end -0.6985 -1.169924)
			(stroke
				(width 0.1)
				(type default)
			)
			(layer "F.Fab")
		)
		(fp_line
			(start -0.6985 -1.169924)
			(end -0.6985 -1.524)
			(stroke
				(width 0.1)
				(type default)
			)
			(layer "F.Fab")
		)
		(fp_line
			(start -0.6985 -1.524)
			(end 0.6985 -1.524)
			(stroke
				(width 0.1)
				(type default)
			)
			(layer "F.Fab")
		)
		(fp_line
			(start 0.6985 -1.524)
			(end 0.6985 -0.219964)
			(stroke
				(width 0.1)
				(type default)
			)
			(layer "F.Fab")
		)
		(fp_rect
			(start -0.6985 1.524)
			(end 0.6985 -1.524)
			(stroke
				(width 0)
				(type default)
			)
			(fill no)
			(layer "F.Fab")
		)
		(pad "D" smd rect
			(at 1.1176 0 180)
			(size 1.016 1.27)
			(layers "F.Cu" "F.Mask" "F.Paste")
			(net "P12V_LED_FAN7")
		)
		(pad "G" smd rect
			(at -1.1176 -1.016 180)
			(size 1.016 1.27)
			(layers "F.Cu" "F.Mask" "F.Paste")
			(net "U412_D1")
		)
		(pad "S" smd rect
			(at -1.1176 1.016 180)
			(size 1.016 1.27)
			(layers "F.Cu" "F.Mask" "F.Paste")
			(net "P12V_LED")
		)
	)
	(footprint ""
		(layer "F.Cu")
		(at 14.859 -133.604)
		(property "Reference" "R5618"
			(at 0 0 0)
			(layer "F.SilkS")
			(hide yes)
			(effects
				(font
					(size 1.27 1.27)
				)
			)
		)
		(property "Value" ""
			(at 0 0 0)
			(layer "F.Fab")
			(effects
				(font
					(size 1.27 1.27)
				)
			)
		)
		(duplicate_pad_numbers_are_jumpers no)
		(fp_line
			(start -0.7874 -0.4064)
			(end 0.7874 -0.4064)
			(stroke
				(width 0.1524)
				(type default)
			)
			(layer "F.SilkS")
		)
		(fp_line
			(start -0.7874 0.4064)
			(end -0.7874 -0.4064)
			(stroke
				(width 0.1524)
				(type default)
			)
			(layer "F.SilkS")
		)
		(fp_line
			(start 0.7874 -0.4064)
			(end 0.7874 0.4064)
			(stroke
				(width 0.1524)
				(type default)
			)
			(layer "F.SilkS")
		)
		(fp_line
			(start 0.7874 0.4064)
			(end -0.7874 0.4064)
			(stroke
				(width 0.1524)
				(type default)
			)
			(layer "F.SilkS")
		)
		(fp_line
			(start -0.67945 -0.305054)
			(end -0.12065 -0.305054)
			(stroke
				(width 0.1)
				(type default)
			)
			(layer "F.Fab")
		)
		(fp_line
			(start -0.67945 0.3048)
			(end -0.67945 -0.305054)
			(stroke
				(width 0.1)
				(type default)
			)
			(layer "F.Fab")
		)
		(fp_line
			(start -0.12065 -0.305054)
			(end -0.12065 -0.2794)
			(stroke
				(width 0.1)
				(type default)
			)
			(layer "F.Fab")
		)
		(fp_line
			(start -0.12065 -0.2794)
			(end 0.12065 -0.2794)
			(stroke
				(width 0.1)
				(type default)
			)
			(layer "F.Fab")
		)
		(fp_line
			(start -0.12065 0.2794)
			(end -0.12065 0.3048)
			(stroke
				(width 0.1)
				(type default)
			)
			(layer "F.Fab")
		)
		(fp_line
			(start -0.12065 0.3048)
			(end -0.67945 0.3048)
			(stroke
				(width 0.1)
				(type default)
			)
			(layer "F.Fab")
		)
		(fp_line
			(start 0.120396 0.2794)
			(end -0.12065 0.2794)
			(stroke
				(width 0.1)
				(type default)
			)
			(layer "F.Fab")
		)
		(fp_line
			(start 0.120396 0.3048)
			(end 0.120396 0.2794)
			(stroke
				(width 0.1)
				(type default)
			)
			(layer "F.Fab")
		)
		(fp_line
			(start 0.12065 -0.3048)
			(end 0.67945 -0.3048)
			(stroke
				(width 0.1)
				(type default)
			)
			(layer "F.Fab")
		)
		(fp_line
			(start 0.12065 -0.2794)
			(end 0.12065 -0.3048)
			(stroke
				(width 0.1)
				(type default)
			)
			(layer "F.Fab")
		)
		(fp_line
			(start 0.67945 -0.3048)
			(end 0.67945 0.3048)
			(stroke
				(width 0.1)
				(type default)
			)
			(layer "F.Fab")
		)
		(fp_line
			(start 0.67945 0.3048)
			(end 0.120396 0.3048)
			(stroke
				(width 0.1)
				(type default)
			)
			(layer "F.Fab")
		)
		(pad "1" smd rect
			(at -0.40005 0 180)
			(size 0.4572 0.508)
			(layers "F.Cu" "F.Mask" "F.Paste")
			(net "FAN_6_TACH_OL")
		)
		(pad "2" smd rect
			(at 0.40005 0 180)
			(size 0.4572 0.508)
			(layers "F.Cu" "F.Mask" "F.Paste")
			(net "FAN_6_TACH_OL_R1")
		)
	)
)
